# BASEBOARD_FAB2 (Tioga Pass) — schematic netlist excerpt (pin names and nets, part order shuffled) for the footprints in the layout excerpt that follows; sources: Cadence DE-HDL packaged netlist, KiCad conversion of Wiwynn_Tioga_Pass_MB.brd

T1P9  TPAD-DIFF-4P-GP  pkg DISCRET-GB3  page 256
  \1\  = L5_73OHM_6INCH_DP
  \2\  = L5_73OHM_6INCH_DN
  GND1  = GND
  GND2  = GND

R5D5  RES  249 0.1% CHIP  pkg 0402  page 37 : A = VSENSE_PMAX_CPU0 ; B = GND

(kicad_pcb
	(version 20260206)
	(generator "pcbnew")
	(generator_version "10.0")
	(general
		(thickness 1.6)
		(legacy_teardrops no)
	)
	(paper "A4")
	(title_block
		(title "Wiwynn_Tioga_Pass_MB.brd")
		(comment 1 "Tioga Pass / footprints 843-844 of 4770")
	)
	(layers
		(0 "F.Cu" signal "TOP")
		(4 "In1.Cu" signal "L2GND")
		(6 "In2.Cu" signal "L3")
		(8 "In3.Cu" signal "L4GND")
		(10 "In4.Cu" signal "L5")
		(12 "In5.Cu" signal "L6GND")
		(14 "In6.Cu" signal "L7VCC")
		(16 "In7.Cu" signal "L8VCC")
		(18 "In8.Cu" signal "L9GND")
		(20 "In9.Cu" signal "L10")
		(22 "In10.Cu" signal "L11GND")
		(24 "In11.Cu" signal "L12")
		(26 "In12.Cu" signal "L13GND")
		(2 "B.Cu" signal "BOTTOM")
		(9 "F.Adhes" user "F.Adhesive")
		(11 "B.Adhes" user "B.Adhesive")
		(13 "F.Paste" user "Package Geometry/Pastemask Top")
		(15 "B.Paste" user "Package Geometry/Pastemask Bottom")
		(5 "F.SilkS" user "Ref Des/Silkscreen Top")
		(7 "B.SilkS" user "Ref Des/Silkscreen Bottom")
		(1 "F.Mask" user "Board Geometry/Soldermask Top")
		(3 "B.Mask" user "Board Geometry/Soldermask Bottom")
		(17 "Dwgs.User" user "User.Drawings")
		(19 "Cmts.User" user "User.Comments")
		(21 "Eco1.User" user "User.Eco1")
		(23 "Eco2.User" user "User.Eco2")
		(25 "Edge.Cuts" user "Board Geometry/Outline")
		(27 "Margin" user)
		(31 "F.CrtYd" user "Package Geometry/Place Bound Top")
		(29 "B.CrtYd" user "Package Geometry/Place Bound Bottom")
		(35 "F.Fab" user "Ref Des/Assembly Top")
		(33 "B.Fab" user "Ref Des/Assembly Bottom")
	)
	(footprint ""
		(layer "F.Cu")
		(at 127.570484 12.014454 -90)
		(property "Reference" "T1P9"
			(at 0 0 270)
			(layer "F.SilkS")
			(hide yes)
			(effects
				(font
					(size 1.27 1.27)
				)
			)
		)
		(property "Value" "*"
			(at -3.302 1.12395 270)
			(unlocked yes)
			(layer "F.Fab")
			(hide yes)
			(effects
				(font
					(size 0.889 0.889)
					(thickness 0.1524)
				)
			)
		)
		(property "Device Type" "TPAD-DIFF-4P-GP_DISCRET-GB3-TPA"
			(at -3.302 -0.40005 270)
			(unlocked yes)
			(layer "F.Fab")
			(hide yes)
			(effects
				(font
					(size 0.889 0.889)
					(thickness 0.1524)
				)
			)
		)
		(duplicate_pad_numbers_are_jumpers no)
		(fp_line
			(start -2.286 2.286)
			(end 2.286 2.286)
			(stroke
				(width 0.1524)
				(type default)
			)
			(layer "F.SilkS")
		)
		(fp_line
			(start 2.286 2.286)
			(end 2.286 -2.286)
			(stroke
				(width 0.1524)
				(type default)
			)
			(layer "F.SilkS")
		)
		(fp_line
			(start -2.286 -2.286)
			(end -2.286 2.286)
			(stroke
				(width 0.1524)
				(type default)
			)
			(layer "F.SilkS")
		)
		(fp_line
			(start 2.286 -2.286)
			(end -2.286 -2.286)
			(stroke
				(width 0.1524)
				(type default)
			)
			(layer "F.SilkS")
		)
		(fp_line
			(start -2.413 -2.413)
			(end -2.413 -1.143)
			(stroke
				(width 0.4064)
				(type default)
			)
			(layer "F.SilkS")
		)
		(fp_line
			(start -1.143 -2.413)
			(end -2.413 -2.413)
			(stroke
				(width 0.4064)
				(type default)
			)
			(layer "F.SilkS")
		)
		(fp_rect
			(start -2.54 2.54)
			(end 2.54 -2.54)
			(stroke
				(width 0)
				(type default)
			)
			(fill no)
			(layer "F.CrtYd")
		)
		(fp_rect
			(start -2.54 2.54)
			(end 2.54 -2.54)
			(stroke
				(width 0)
				(type default)
			)
			(fill no)
			(layer "F.Fab")
		)
		(pad "1" thru_hole circle
			(at -1.27 -1.27 270)
			(size 1.524 1.524)
			(drill 0.9144)
			(layers "*.Cu" "*.Mask")
			(remove_unused_layers no)
			(net "L5_73OHM_6INCH_DP")
			(clearance -0.0508)
			(thermal_gap 0.127)
			(padstack
				(mode front_inner_back)
				(layer "Inner"
					(shape circle)
					(size 1.1684 1.1684)
					(clearance 0.127)
				)
				(layer "B.Cu"
					(shape circle)
					(size 1.524 1.524)
					(clearance -0.0508)
				)
			)
		)
		(pad "2" thru_hole circle
			(at 1.27 -1.27 270)
			(size 1.524 1.524)
			(drill 0.9144)
			(layers "*.Cu" "*.Mask")
			(remove_unused_layers no)
			(net "L5_73OHM_6INCH_DN")
			(clearance -0.0508)
			(thermal_gap 0.127)
			(padstack
				(mode front_inner_back)
				(layer "Inner"
					(shape circle)
					(size 1.1684 1.1684)
					(clearance 0.127)
				)
				(layer "B.Cu"
					(shape circle)
					(size 1.524 1.524)
					(clearance -0.0508)
				)
			)
		)
		(pad "GND1" thru_hole rect
			(at -1.27 1.27 270)
			(size 1.524 1.524)
			(drill 0.9144)
			(layers "*.Cu" "*.Mask")
			(remove_unused_layers no)
			(net "GND")
			(clearance -0.0508)
			(thermal_gap 0.127)
			(padstack
				(mode front_inner_back)
				(layer "Inner"
					(shape circle)
					(size 1.1684 1.1684)
					(clearance 0.127)
				)
				(layer "B.Cu"
					(shape rect)
					(size 1.524 1.524)
					(clearance -0.0508)
				)
			)
		)
		(pad "GND2" thru_hole rect
			(at 1.27 1.27 270)
			(size 1.524 1.524)
			(drill 0.9144)
			(layers "*.Cu" "*.Mask")
			(remove_unused_layers no)
			(net "GND")
			(clearance -0.0508)
			(thermal_gap 0.127)
			(padstack
				(mode front_inner_back)
				(layer "Inner"
					(shape circle)
					(size 1.1684 1.1684)
					(clearance 0.127)
				)
				(layer "B.Cu"
					(shape rect)
					(size 1.524 1.524)
					(clearance -0.0508)
				)
			)
		)
	)
	(footprint ""
		(layer "F.Cu")
		(at 273.8628 -68.072 90)
		(property "Reference" "R5D5"
			(at 0 0 90)
			(layer "F.SilkS")
			(hide yes)
			(effects
				(font
					(size 1.27 1.27)
				)
			)
		)
		(property "Value" ""
			(at 0 0 90)
			(layer "F.Fab")
			(effects
				(font
					(size 1.27 1.27)
				)
			)
		)
		(duplicate_pad_numbers_are_jumpers no)
		(fp_poly
			(pts
				(xy -0.2794 -0.1016) (xy 0.2794 -0.1016) (xy 0.2794 0.9906) (xy -0.2794 0.9906)
			)
			(stroke
				(width 0)
				(type default)
			)
			(fill no)
			(layer "F.CrtYd")
		)
		(fp_line
			(start 0.2794 -0.1016)
			(end -0.2794 -0.1016)
			(stroke
				(width 0.1)
				(type default)
			)
			(layer "F.Fab")
		)
		(fp_line
			(start -0.2794 -0.1016)
			(end -0.2794 0.9906)
			(stroke
				(width 0.1)
				(type default)
			)
			(layer "F.Fab")
		)
		(fp_line
			(start 0.2794 0.9906)
			(end 0.2794 -0.1016)
			(stroke
				(width 0.1)
				(type default)
			)
			(layer "F.Fab")
		)
		(fp_line
			(start -0.2794 0.9906)
			(end 0.2794 0.9906)
			(stroke
				(width 0.1)
				(type default)
			)
			(layer "F.Fab")
		)
		(pad "1" smd rect
			(at 0 0 90)
			(size 0.508 0.508)
			(layers "F.Cu" "F.Mask" "F.Paste")
			(net "VSENSE_PMAX_CPU0")
		)
		(pad "2" smd rect
			(at 0 0.889 90)
			(size 0.508 0.508)
			(layers "F.Cu" "F.Mask" "F.Paste")
			(net "GND")
		)
		(zone
			(layer "F.Cu")
			(hatch none 0.5)
			(connect_pads
				(clearance 0)
			)
			(min_thickness 0.25)
			(keepout
				(tracks allowed)
				(vias not_allowed)
				(pads allowed)
				(copperpour not_allowed)
				(footprints allowed)
			)
			(placement
				(enabled no)
				(sheetname "")
			)
			(fill
				(thermal_gap 0.5)
				(thermal_bridge_width 0.5)
				(island_removal_mode 0)
			)
			(polygon
				(pts
					(xy 274.1168 -67.818) (xy 274.1168 -68.326) (xy 274.4978 -68.326) (xy 274.4978 -67.818)
				)
			)
		)
		(zone
			(layer "F.Cu")
			(hatch none 0.5)
			(connect_pads
				(clearance 0)
			)
			(min_thickness 0.25)
			(keepout
				(tracks not_allowed)
				(vias allowed)
				(pads allowed)
				(copperpour not_allowed)
				(footprints allowed)
			)
			(placement
				(enabled no)
				(sheetname "")
			)
			(fill
				(thermal_gap 0.5)
				(thermal_bridge_width 0.5)
				(island_removal_mode 0)
			)
			(polygon
				(pts
					(xy 274.4978 -67.818) (xy 274.4978 -68.326) (xy 274.1168 -68.326) (xy 274.1168 -67.818)
				)
			)
		)
	)
)
